# SCM (Grand Teton) — schematic netlist excerpt (pin names and nets, part order shuffled) for the footprints in the layout excerpt that follows; sources: Cadence DE-HDL packaged netlist, KiCad conversion of 12092022_DA0F0TMDCD0_F0T_Management_Board_D_brd_V3_OCP.brd

R82  Q_RES  2K 1% CHIP  pkg 0402LF  page 11 : A = P3V3_AUX ; B = SGPIO_CLK_0

(kicad_pcb
	(version 20260206)
	(generator "pcbnew")
	(generator_version "10.0")
	(general
		(thickness 1.6)
		(legacy_teardrops no)
	)
	(paper "A4")
	(title_block
		(title "12092022_DA0F0TMDCD0_F0T_Management_Board_D_brd_V3_OCP.brd")
		(comment 1 "Grand Teton / footprints 657-657 of 1440")
	)
	(layers
		(0 "F.Cu" signal "TOP")
		(4 "In1.Cu" signal "GND")
		(6 "In2.Cu" signal "IN1")
		(8 "In3.Cu" signal "GND1")
		(10 "In4.Cu" signal "IN2")
		(12 "In5.Cu" signal "VCC")
		(14 "In6.Cu" signal "VCC1")
		(16 "In7.Cu" signal "IN3")
		(18 "In8.Cu" signal "GND2")
		(20 "In9.Cu" signal "IN4")
		(22 "In10.Cu" signal "GND3")
		(2 "B.Cu" signal "BOTTOM")
		(9 "F.Adhes" user "F.Adhesive")
		(11 "B.Adhes" user "B.Adhesive")
		(13 "F.Paste" user "Package Geometry/Pastemask Top")
		(15 "B.Paste" user "Package Geometry/Pastemask Bottom")
		(5 "F.SilkS" user "Ref Des/Silkscreen Top")
		(7 "B.SilkS" user "Ref Des/Silkscreen Bottom")
		(1 "F.Mask" user "Board Geometry/Soldermask Top")
		(3 "B.Mask" user "Board Geometry/Soldermask Bottom")
		(17 "Dwgs.User" user "User.Drawings")
		(19 "Cmts.User" user "User.Comments")
		(21 "Eco1.User" user "User.Eco1")
		(23 "Eco2.User" user "User.Eco2")
		(25 "Edge.Cuts" user "Board Geometry/Outline")
		(27 "Margin" user)
		(31 "F.CrtYd" user "Package Geometry/Place Bound Top")
		(29 "B.CrtYd" user "Package Geometry/Place Bound Bottom")
		(35 "F.Fab" user "Ref Des/Assembly Top")
		(33 "B.Fab" user "Ref Des/Assembly Bottom")
	)
	(footprint ""
		(layer "F.Cu")
		(at 44.704 -109.8804)
		(property "Reference" "R82"
			(at 0 0 0)
			(layer "F.SilkS")
			(hide yes)
			(effects
				(font
					(size 1.27 1.27)
				)
			)
		)
		(property "Value" ""
			(at 0 0 0)
			(layer "F.Fab")
			(effects
				(font
					(size 1.27 1.27)
				)
			)
		)
		(duplicate_pad_numbers_are_jumpers no)
		(fp_line
			(start -0.7874 -0.4064)
			(end 0.7874 -0.4064)
			(stroke
				(width 0.1524)
				(type default)
			)
			(layer "F.SilkS")
		)
		(fp_line
			(start -0.7874 0.4064)
			(end -0.7874 -0.4064)
			(stroke
				(width 0.1524)
				(type default)
			)
			(layer "F.SilkS")
		)
		(fp_line
			(start 0.7874 -0.4064)
			(end 0.7874 0.4064)
			(stroke
				(width 0.1524)
				(type default)
			)
			(layer "F.SilkS")
		)
		(fp_line
			(start 0.7874 0.4064)
			(end -0.7874 0.4064)
			(stroke
				(width 0.1524)
				(type default)
			)
			(layer "F.SilkS")
		)
		(fp_line
			(start -0.67945 -0.305054)
			(end -0.12065 -0.305054)
			(stroke
				(width 0.1)
				(type default)
			)
			(layer "F.Fab")
		)
		(fp_line
			(start -0.67945 0.3048)
			(end -0.67945 -0.305054)
			(stroke
				(width 0.1)
				(type default)
			)
			(layer "F.Fab")
		)
		(fp_line
			(start -0.12065 -0.305054)
			(end -0.12065 -0.2794)
			(stroke
				(width 0.1)
				(type default)
			)
			(layer "F.Fab")
		)
		(fp_line
			(start -0.12065 -0.2794)
			(end 0.12065 -0.2794)
			(stroke
				(width 0.1)
				(type default)
			)
			(layer "F.Fab")
		)
		(fp_line
			(start -0.12065 0.2794)
			(end -0.12065 0.3048)
			(stroke
				(width 0.1)
				(type default)
			)
			(layer "F.Fab")
		)
		(fp_line
			(start -0.12065 0.3048)
			(end -0.67945 0.3048)
			(stroke
				(width 0.1)
				(type default)
			)
			(layer "F.Fab")
		)
		(fp_line
			(start 0.120396 0.2794)
			(end -0.12065 0.2794)
			(stroke
				(width 0.1)
				(type default)
			)
			(layer "F.Fab")
		)
		(fp_line
			(start 0.120396 0.3048)
			(end 0.120396 0.2794)
			(stroke
				(width 0.1)
				(type default)
			)
			(layer "F.Fab")
		)
		(fp_line
			(start 0.12065 -0.3048)
			(end 0.67945 -0.3048)
			(stroke
				(width 0.1)
				(type default)
			)
			(layer "F.Fab")
		)
		(fp_line
			(start 0.12065 -0.2794)
			(end 0.12065 -0.3048)
			(stroke
				(width 0.1)
				(type default)
			)
			(layer "F.Fab")
		)
		(fp_line
			(start 0.67945 -0.3048)
			(end 0.67945 0.3048)
			(stroke
				(width 0.1)
				(type default)
			)
			(layer "F.Fab")
		)
		(fp_line
			(start 0.67945 0.3048)
			(end 0.120396 0.3048)
			(stroke
				(width 0.1)
				(type default)
			)
			(layer "F.Fab")
		)
		(pad "1" smd circle
			(at -0.40005 0)
			(size 0 0)
			(layers "F.Cu" "F.Mask" "F.Paste")
			(net "P3V3_AUX")
		)
		(pad "2" smd circle
			(at 0.40005 0)
			(size 0 0)
			(layers "F.Cu" "F.Mask" "F.Paste")
			(net "SGPIO_CLK_0")
		)
	)
)
